FILE_TYPE=LIBRARY_PARTS;
primitive 'NC7SB3157P6X';
  pin
    'B1':
      PIN_NUMBER='(1)';
      BIDIRECTIONAL='TRUE';
      INPUT_LOAD='(-0.01,0.01)';
      OUTPUT_LOAD='(1.0,-1.0)';
    'GND':
      PIN_NUMBER='(2)';
      PINUSE='POWER';
      NO_LOAD_CHECK='Both';
      NO_IO_CHECK='Both';
      NO_ASSERT_CHECK='TRUE';
      NO_DIR_CHECK='TRUE';
      ALLOW_CONNECT='TRUE';
    'B0':
      PIN_NUMBER='(3)';
      BIDIRECTIONAL='TRUE';
      INPUT_LOAD='(-0.01,0.01)';
      OUTPUT_LOAD='(1.0,-1.0)';
    'S':
      PIN_NUMBER='(6)';
      INPUT_LOAD='(-0.01,0.01)';
    'VCC':
      PIN_NUMBER='(5)';
      PINUSE='POWER';
      NO_LOAD_CHECK='Both';
      NO_IO_CHECK='Both';
      NO_ASSERT_CHECK='TRUE';
      NO_DIR_CHECK='TRUE';
      ALLOW_CONNECT='TRUE';
    'A':
      PIN_NUMBER='(4)';
      BIDIRECTIONAL='TRUE';
      INPUT_LOAD='(-0.01,0.01)';
      OUTPUT_LOAD='(1.0,-1.0)';
  end_pin;
  body
    PART_NAME='NC7SB3157P6X';
    BODY_NAME='NC7SB3157P6X';
    PHYS_DES_PREFIX='U';
    CLASS='IC';
  end_body;
end_primitive;

END.
